# T6G (Grand Teton) — schematic netlist excerpt (pin names and nets, part order shuffled) for the footprints in the layout excerpt that follows; sources: Cadence DE-HDL packaged netlist, KiCad conversion of 04192023_DAF0TMB3IC0_F0TG_MB_C_brd_V02_OCP.brd

R8009  Q_RES  10K 5% CHIP  pkg 0402LF  page 226 : A = P3V3_AUX ; B = PWRGD_PVDD18_S5_P1
R187  Q_RES  0 5% CHIP  pkg 0402LF  page 82 : A = IRQ_CPU_BMC_NMI_N ; B = IRQ_CPU_BMC_NMI_R_N
C810  Q_CAP_DIFFBUS  DIFF BUS_0.22UF 6.3V 20% X6S  pkg C0201  page 65 : \1\ = P5E_CPU1_P0_TX_C_DN<13> ; \2\ = P5E_CPU1_P0_TX_DN<13>

(kicad_pcb
	(version 20260206)
	(generator "pcbnew")
	(generator_version "10.0")
	(general
		(thickness 1.6)
		(legacy_teardrops no)
	)
	(paper "A4")
	(title_block
		(title "04192023_DAF0TMB3IC0_F0TG_MB_C_brd_V02_OCP.brd")
		(comment 1 "Grand Teton / footprints 3909-3911 of 8354")
	)
	(layers
		(0 "F.Cu" signal "TOP")
		(4 "In1.Cu" signal "GND")
		(6 "In2.Cu" signal "IN1")
		(8 "In3.Cu" signal "GND1")
		(10 "In4.Cu" signal "IN2")
		(12 "In5.Cu" signal "GND2")
		(14 "In6.Cu" signal "IN3")
		(16 "In7.Cu" signal "GND3")
		(18 "In8.Cu" signal "VCC")
		(20 "In9.Cu" signal "VCC1")
		(22 "In10.Cu" signal "GND4")
		(24 "In11.Cu" signal "IN4")
		(26 "In12.Cu" signal "GND5")
		(28 "In13.Cu" signal "IN5")
		(30 "In14.Cu" signal "GND6")
		(32 "In15.Cu" signal "IN6")
		(34 "In16.Cu" signal "GND7")
		(2 "B.Cu" signal "BOTTOM")
		(9 "F.Adhes" user "F.Adhesive")
		(11 "B.Adhes" user "B.Adhesive")
		(13 "F.Paste" user "Package Geometry/Pastemask Top")
		(15 "B.Paste" user "Package Geometry/Pastemask Bottom")
		(5 "F.SilkS" user "Ref Des/Silkscreen Top")
		(7 "B.SilkS" user "Ref Des/Silkscreen Bottom")
		(1 "F.Mask" user "Board Geometry/Soldermask Top")
		(3 "B.Mask" user "Board Geometry/Soldermask Bottom")
		(17 "Dwgs.User" user "User.Drawings")
		(19 "Cmts.User" user "User.Comments")
		(21 "Eco1.User" user "User.Eco1")
		(23 "Eco2.User" user "User.Eco2")
		(25 "Edge.Cuts" user "Board Geometry/Outline")
		(27 "Margin" user)
		(31 "F.CrtYd" user "Package Geometry/Place Bound Top")
		(29 "B.CrtYd" user "Package Geometry/Place Bound Bottom")
		(35 "F.Fab" user "Ref Des/Assembly Top")
		(33 "B.Fab" user "Ref Des/Assembly Bottom")
	)
	(footprint ""
		(layer "F.Cu")
		(at 68.516754 -370.57203 -90)
		(property "Reference" "C810"
			(at 0 0 270)
			(layer "F.SilkS")
			(hide yes)
			(effects
				(font
					(size 1.27 1.27)
				)
			)
		)
		(property "Value" ""
			(at 0 0 270)
			(layer "F.Fab")
			(effects
				(font
					(size 1.27 1.27)
				)
			)
		)
		(duplicate_pad_numbers_are_jumpers no)
		(fp_line
			(start -0.299974 0.150114)
			(end -0.299974 -0.150114)
			(stroke
				(width 0.1)
				(type default)
			)
			(layer "F.Fab")
		)
		(fp_line
			(start 0.299974 0.150114)
			(end -0.299974 0.150114)
			(stroke
				(width 0.1)
				(type default)
			)
			(layer "F.Fab")
		)
		(fp_line
			(start -0.299974 -0.150114)
			(end 0.299974 -0.150114)
			(stroke
				(width 0.1)
				(type default)
			)
			(layer "F.Fab")
		)
		(fp_line
			(start 0.299974 -0.150114)
			(end 0.299974 0.150114)
			(stroke
				(width 0.1)
				(type default)
			)
			(layer "F.Fab")
		)
		(pad "1" smd rect
			(at -0.2667 0 270)
			(size 0.3048 0.381)
			(layers "F.Cu" "F.Mask" "F.Paste")
			(net "P5E_CPU1_P0_TX_C_DN<13>")
		)
		(pad "2" smd rect
			(at 0.2667 0 270)
			(size 0.3048 0.381)
			(layers "F.Cu" "F.Mask" "F.Paste")
			(net "P5E_CPU1_P0_TX_DN<13>")
		)
	)
	(footprint ""
		(layer "F.Cu")
		(at 75.64501 -148.451316 90)
		(property "Reference" "R8009"
			(at 0 0 90)
			(layer "F.SilkS")
			(hide yes)
			(effects
				(font
					(size 1.27 1.27)
				)
			)
		)
		(property "Value" ""
			(at 0 0 90)
			(layer "F.Fab")
			(effects
				(font
					(size 1.27 1.27)
				)
			)
		)
		(duplicate_pad_numbers_are_jumpers no)
		(fp_line
			(start 0.7874 -0.4064)
			(end 0.7874 0.4064)
			(stroke
				(width 0.1524)
				(type default)
			)
			(layer "F.SilkS")
		)
		(fp_line
			(start -0.7874 -0.4064)
			(end 0.7874 -0.4064)
			(stroke
				(width 0.1524)
				(type default)
			)
			(layer "F.SilkS")
		)
		(fp_line
			(start 0.7874 0.4064)
			(end -0.7874 0.4064)
			(stroke
				(width 0.1524)
				(type default)
			)
			(layer "F.SilkS")
		)
		(fp_line
			(start -0.7874 0.4064)
			(end -0.7874 -0.4064)
			(stroke
				(width 0.1524)
				(type default)
			)
			(layer "F.SilkS")
		)
		(fp_line
			(start -0.12065 -0.305054)
			(end -0.12065 -0.2794)
			(stroke
				(width 0.1)
				(type default)
			)
			(layer "F.Fab")
		)
		(fp_line
			(start -0.67945 -0.305054)
			(end -0.12065 -0.305054)
			(stroke
				(width 0.1)
				(type default)
			)
			(layer "F.Fab")
		)
		(fp_line
			(start 0.67945 -0.3048)
			(end 0.67945 0.3048)
			(stroke
				(width 0.1)
				(type default)
			)
			(layer "F.Fab")
		)
		(fp_line
			(start 0.12065 -0.3048)
			(end 0.67945 -0.3048)
			(stroke
				(width 0.1)
				(type default)
			)
			(layer "F.Fab")
		)
		(fp_line
			(start 0.12065 -0.2794)
			(end 0.12065 -0.3048)
			(stroke
				(width 0.1)
				(type default)
			)
			(layer "F.Fab")
		)
		(fp_line
			(start -0.12065 -0.2794)
			(end 0.12065 -0.2794)
			(stroke
				(width 0.1)
				(type default)
			)
			(layer "F.Fab")
		)
		(fp_line
			(start 0.120396 0.2794)
			(end -0.12065 0.2794)
			(stroke
				(width 0.1)
				(type default)
			)
			(layer "F.Fab")
		)
		(fp_line
			(start -0.12065 0.2794)
			(end -0.12065 0.3048)
			(stroke
				(width 0.1)
				(type default)
			)
			(layer "F.Fab")
		)
		(fp_line
			(start 0.67945 0.3048)
			(end 0.120396 0.3048)
			(stroke
				(width 0.1)
				(type default)
			)
			(layer "F.Fab")
		)
		(fp_line
			(start 0.120396 0.3048)
			(end 0.120396 0.2794)
			(stroke
				(width 0.1)
				(type default)
			)
			(layer "F.Fab")
		)
		(fp_line
			(start -0.12065 0.3048)
			(end -0.67945 0.3048)
			(stroke
				(width 0.1)
				(type default)
			)
			(layer "F.Fab")
		)
		(fp_line
			(start -0.67945 0.3048)
			(end -0.67945 -0.305054)
			(stroke
				(width 0.1)
				(type default)
			)
			(layer "F.Fab")
		)
		(pad "1" smd circle
			(at -0.40005 0 90)
			(size 0 0)
			(layers "F.Cu" "F.Mask" "F.Paste")
			(net "P3V3_AUX")
		)
		(pad "2" smd circle
			(at 0.40005 0 90)
			(size 0 0)
			(layers "F.Cu" "F.Mask" "F.Paste")
			(net "PWRGD_PVDD18_S5_P1")
		)
	)
	(footprint ""
		(layer "F.Cu")
		(at 179.9082 -96.103948 90)
		(property "Reference" "R187"
			(at 0 0 90)
			(layer "F.SilkS")
			(hide yes)
			(effects
				(font
					(size 1.27 1.27)
				)
			)
		)
		(property "Value" ""
			(at 0 0 90)
			(layer "F.Fab")
			(effects
				(font
					(size 1.27 1.27)
				)
			)
		)
		(duplicate_pad_numbers_are_jumpers no)
		(fp_line
			(start 0.7874 -0.4064)
			(end 0.7874 0.4064)
			(stroke
				(width 0.1524)
				(type default)
			)
			(layer "F.SilkS")
		)
		(fp_line
			(start -0.7874 -0.4064)
			(end 0.7874 -0.4064)
			(stroke
				(width 0.1524)
				(type default)
			)
			(layer "F.SilkS")
		)
		(fp_line
			(start 0.7874 0.4064)
			(end -0.7874 0.4064)
			(stroke
				(width 0.1524)
				(type default)
			)
			(layer "F.SilkS")
		)
		(fp_line
			(start -0.7874 0.4064)
			(end -0.7874 -0.4064)
			(stroke
				(width 0.1524)
				(type default)
			)
			(layer "F.SilkS")
		)
		(fp_line
			(start -0.12065 -0.305054)
			(end -0.12065 -0.2794)
			(stroke
				(width 0.1)
				(type default)
			)
			(layer "F.Fab")
		)
		(fp_line
			(start -0.67945 -0.305054)
			(end -0.12065 -0.305054)
			(stroke
				(width 0.1)
				(type default)
			)
			(layer "F.Fab")
		)
		(fp_line
			(start 0.67945 -0.3048)
			(end 0.67945 0.3048)
			(stroke
				(width 0.1)
				(type default)
			)
			(layer "F.Fab")
		)
		(fp_line
			(start 0.12065 -0.3048)
			(end 0.67945 -0.3048)
			(stroke
				(width 0.1)
				(type default)
			)
			(layer "F.Fab")
		)
		(fp_line
			(start 0.12065 -0.2794)
			(end 0.12065 -0.3048)
			(stroke
				(width 0.1)
				(type default)
			)
			(layer "F.Fab")
		)
		(fp_line
			(start -0.12065 -0.2794)
			(end 0.12065 -0.2794)
			(stroke
				(width 0.1)
				(type default)
			)
			(layer "F.Fab")
		)
		(fp_line
			(start 0.120396 0.2794)
			(end -0.12065 0.2794)
			(stroke
				(width 0.1)
				(type default)
			)
			(layer "F.Fab")
		)
		(fp_line
			(start -0.12065 0.2794)
			(end -0.12065 0.3048)
			(stroke
				(width 0.1)
				(type default)
			)
			(layer "F.Fab")
		)
		(fp_line
			(start 0.67945 0.3048)
			(end 0.120396 0.3048)
			(stroke
				(width 0.1)
				(type default)
			)
			(layer "F.Fab")
		)
		(fp_line
			(start 0.120396 0.3048)
			(end 0.120396 0.2794)
			(stroke
				(width 0.1)
				(type default)
			)
			(layer "F.Fab")
		)
		(fp_line
			(start -0.12065 0.3048)
			(end -0.67945 0.3048)
			(stroke
				(width 0.1)
				(type default)
			)
			(layer "F.Fab")
		)
		(fp_line
			(start -0.67945 0.3048)
			(end -0.67945 -0.305054)
			(stroke
				(width 0.1)
				(type default)
			)
			(layer "F.Fab")
		)
		(pad "1" smd circle
			(at -0.40005 0 90)
			(size 0 0)
			(layers "F.Cu" "F.Mask" "F.Paste")
			(net "IRQ_CPU_BMC_NMI_N")
		)
		(pad "2" smd circle
			(at 0.40005 0 90)
			(size 0 0)
			(layers "F.Cu" "F.Mask" "F.Paste")
			(net "IRQ_CPU_BMC_NMI_R_N")
		)
	)
)
